# T6G (Grand Teton) — schematic netlist excerpt (pin names and nets, part order shuffled) for the footprints in the layout excerpt that follows; sources: Cadence DE-HDL packaged netlist, KiCad conversion of 04192023_DAF0TMB3IC0_F0TG_MB_C_brd_V02_OCP.brd

PC319  Q_CAP  2.2UF 10V 10% X6S  pkg C0402  page 215 : A = PVDDCR_SOC_P1_VCC1 ; B = GND
R4139  Q_RES  4.7K 5% CHIP  pkg 0402LF  page 125 : A = P3V3_AUX ; B = PRSNT_CABLE_GPU_A2

(kicad_pcb
	(version 20260206)
	(generator "pcbnew")
	(generator_version "10.0")
	(general
		(thickness 1.6)
		(legacy_teardrops no)
	)
	(paper "A4")
	(title_block
		(title "04192023_DAF0TMB3IC0_F0TG_MB_C_brd_V02_OCP.brd")
		(comment 1 "Grand Teton / footprints 2926-2927 of 8354")
	)
	(layers
		(0 "F.Cu" signal "TOP")
		(4 "In1.Cu" signal "GND")
		(6 "In2.Cu" signal "IN1")
		(8 "In3.Cu" signal "GND1")
		(10 "In4.Cu" signal "IN2")
		(12 "In5.Cu" signal "GND2")
		(14 "In6.Cu" signal "IN3")
		(16 "In7.Cu" signal "GND3")
		(18 "In8.Cu" signal "VCC")
		(20 "In9.Cu" signal "VCC1")
		(22 "In10.Cu" signal "GND4")
		(24 "In11.Cu" signal "IN4")
		(26 "In12.Cu" signal "GND5")
		(28 "In13.Cu" signal "IN5")
		(30 "In14.Cu" signal "GND6")
		(32 "In15.Cu" signal "IN6")
		(34 "In16.Cu" signal "GND7")
		(2 "B.Cu" signal "BOTTOM")
		(9 "F.Adhes" user "F.Adhesive")
		(11 "B.Adhes" user "B.Adhesive")
		(13 "F.Paste" user "Package Geometry/Pastemask Top")
		(15 "B.Paste" user "Package Geometry/Pastemask Bottom")
		(5 "F.SilkS" user "Ref Des/Silkscreen Top")
		(7 "B.SilkS" user "Ref Des/Silkscreen Bottom")
		(1 "F.Mask" user "Board Geometry/Soldermask Top")
		(3 "B.Mask" user "Board Geometry/Soldermask Bottom")
		(17 "Dwgs.User" user "User.Drawings")
		(19 "Cmts.User" user "User.Comments")
		(21 "Eco1.User" user "User.Eco1")
		(23 "Eco2.User" user "User.Eco2")
		(25 "Edge.Cuts" user "Board Geometry/Outline")
		(27 "Margin" user)
		(31 "F.CrtYd" user "Package Geometry/Place Bound Top")
		(29 "B.CrtYd" user "Package Geometry/Place Bound Bottom")
		(35 "F.Fab" user "Ref Des/Assembly Top")
		(33 "B.Fab" user "Ref Des/Assembly Bottom")
	)
	(footprint ""
		(layer "F.Cu")
		(at 119.36857 -169.258234 -90)
		(property "Reference" "PC319"
			(at 0 0 270)
			(layer "F.SilkS")
			(hide yes)
			(effects
				(font
					(size 1.27 1.27)
				)
			)
		)
		(property "Value" ""
			(at 0 0 270)
			(layer "F.Fab")
			(effects
				(font
					(size 1.27 1.27)
				)
			)
		)
		(duplicate_pad_numbers_are_jumpers no)
		(fp_line
			(start -0.7874 0.4064)
			(end -0.7874 -0.4064)
			(stroke
				(width 0.1524)
				(type default)
			)
			(layer "F.SilkS")
		)
		(fp_line
			(start -0.286766 0.4064)
			(end -0.7874 0.4064)
			(stroke
				(width 0.1524)
				(type default)
			)
			(layer "F.SilkS")
		)
		(fp_line
			(start 0.7874 0.4064)
			(end 0.348234 0.4064)
			(stroke
				(width 0.1524)
				(type default)
			)
			(layer "F.SilkS")
		)
		(fp_line
			(start -0.7874 -0.4064)
			(end 0.7874 -0.4064)
			(stroke
				(width 0.1524)
				(type default)
			)
			(layer "F.SilkS")
		)
		(fp_line
			(start 0.7874 -0.4064)
			(end 0.7874 0.4064)
			(stroke
				(width 0.1524)
				(type default)
			)
			(layer "F.SilkS")
		)
		(fp_line
			(start -0.67945 0.3048)
			(end -0.67945 -0.305054)
			(stroke
				(width 0.1)
				(type default)
			)
			(layer "F.Fab")
		)
		(fp_line
			(start -0.12065 0.3048)
			(end -0.67945 0.3048)
			(stroke
				(width 0.1)
				(type default)
			)
			(layer "F.Fab")
		)
		(fp_line
			(start 0.120396 0.3048)
			(end 0.120396 0.2794)
			(stroke
				(width 0.1)
				(type default)
			)
			(layer "F.Fab")
		)
		(fp_line
			(start 0.67945 0.3048)
			(end 0.120396 0.3048)
			(stroke
				(width 0.1)
				(type default)
			)
			(layer "F.Fab")
		)
		(fp_line
			(start -0.12065 0.2794)
			(end -0.12065 0.3048)
			(stroke
				(width 0.1)
				(type default)
			)
			(layer "F.Fab")
		)
		(fp_line
			(start 0.120396 0.2794)
			(end -0.12065 0.2794)
			(stroke
				(width 0.1)
				(type default)
			)
			(layer "F.Fab")
		)
		(fp_line
			(start -0.12065 -0.2794)
			(end 0.12065 -0.2794)
			(stroke
				(width 0.1)
				(type default)
			)
			(layer "F.Fab")
		)
		(fp_line
			(start 0.12065 -0.2794)
			(end 0.12065 -0.3048)
			(stroke
				(width 0.1)
				(type default)
			)
			(layer "F.Fab")
		)
		(fp_line
			(start 0.12065 -0.3048)
			(end 0.67945 -0.3048)
			(stroke
				(width 0.1)
				(type default)
			)
			(layer "F.Fab")
		)
		(fp_line
			(start 0.67945 -0.3048)
			(end 0.67945 0.3048)
			(stroke
				(width 0.1)
				(type default)
			)
			(layer "F.Fab")
		)
		(fp_line
			(start -0.67945 -0.305054)
			(end -0.12065 -0.305054)
			(stroke
				(width 0.1)
				(type default)
			)
			(layer "F.Fab")
		)
		(fp_line
			(start -0.12065 -0.305054)
			(end -0.12065 -0.2794)
			(stroke
				(width 0.1)
				(type default)
			)
			(layer "F.Fab")
		)
		(pad "1" smd circle
			(at -0.40005 0 270)
			(size 0 0)
			(layers "F.Cu" "F.Mask" "F.Paste")
			(net "PVDDCR_SOC_P1_VCC1")
		)
		(pad "2" smd circle
			(at 0.40005 0 270)
			(size 0 0)
			(layers "F.Cu" "F.Mask" "F.Paste")
			(net "GND")
		)
	)
	(footprint ""
		(layer "F.Cu")
		(at 306.501038 -424.956986)
		(property "Reference" "R4139"
			(at 0 0 0)
			(layer "F.SilkS")
			(hide yes)
			(effects
				(font
					(size 1.27 1.27)
				)
			)
		)
		(property "Value" ""
			(at 0 0 0)
			(layer "F.Fab")
			(effects
				(font
					(size 1.27 1.27)
				)
			)
		)
		(duplicate_pad_numbers_are_jumpers no)
		(fp_line
			(start -0.7874 -0.4064)
			(end 0.7874 -0.4064)
			(stroke
				(width 0.1524)
				(type default)
			)
			(layer "F.SilkS")
		)
		(fp_line
			(start -0.7874 0.4064)
			(end -0.7874 -0.4064)
			(stroke
				(width 0.1524)
				(type default)
			)
			(layer "F.SilkS")
		)
		(fp_line
			(start 0.7874 -0.4064)
			(end 0.7874 0.4064)
			(stroke
				(width 0.1524)
				(type default)
			)
			(layer "F.SilkS")
		)
		(fp_line
			(start 0.7874 0.4064)
			(end -0.7874 0.4064)
			(stroke
				(width 0.1524)
				(type default)
			)
			(layer "F.SilkS")
		)
		(fp_line
			(start -0.67945 -0.305054)
			(end -0.12065 -0.305054)
			(stroke
				(width 0.1)
				(type default)
			)
			(layer "F.Fab")
		)
		(fp_line
			(start -0.67945 0.3048)
			(end -0.67945 -0.305054)
			(stroke
				(width 0.1)
				(type default)
			)
			(layer "F.Fab")
		)
		(fp_line
			(start -0.12065 -0.305054)
			(end -0.12065 -0.2794)
			(stroke
				(width 0.1)
				(type default)
			)
			(layer "F.Fab")
		)
		(fp_line
			(start -0.12065 -0.2794)
			(end 0.12065 -0.2794)
			(stroke
				(width 0.1)
				(type default)
			)
			(layer "F.Fab")
		)
		(fp_line
			(start -0.12065 0.2794)
			(end -0.12065 0.3048)
			(stroke
				(width 0.1)
				(type default)
			)
			(layer "F.Fab")
		)
		(fp_line
			(start -0.12065 0.3048)
			(end -0.67945 0.3048)
			(stroke
				(width 0.1)
				(type default)
			)
			(layer "F.Fab")
		)
		(fp_line
			(start 0.120396 0.2794)
			(end -0.12065 0.2794)
			(stroke
				(width 0.1)
				(type default)
			)
			(layer "F.Fab")
		)
		(fp_line
			(start 0.120396 0.3048)
			(end 0.120396 0.2794)
			(stroke
				(width 0.1)
				(type default)
			)
			(layer "F.Fab")
		)
		(fp_line
			(start 0.12065 -0.3048)
			(end 0.67945 -0.3048)
			(stroke
				(width 0.1)
				(type default)
			)
			(layer "F.Fab")
		)
		(fp_line
			(start 0.12065 -0.2794)
			(end 0.12065 -0.3048)
			(stroke
				(width 0.1)
				(type default)
			)
			(layer "F.Fab")
		)
		(fp_line
			(start 0.67945 -0.3048)
			(end 0.67945 0.3048)
			(stroke
				(width 0.1)
				(type default)
			)
			(layer "F.Fab")
		)
		(fp_line
			(start 0.67945 0.3048)
			(end 0.120396 0.3048)
			(stroke
				(width 0.1)
				(type default)
			)
			(layer "F.Fab")
		)
		(pad "1" smd circle
			(at -0.40005 0)
			(size 0 0)
			(layers "F.Cu" "F.Mask" "F.Paste")
			(net "P3V3_AUX")
		)
		(pad "2" smd circle
			(at 0.40005 0)
			(size 0 0)
			(layers "F.Cu" "F.Mask" "F.Paste")
			(net "PRSNT_CABLE_GPU_A2")
		)
	)
)
